M48
INCH,TZ
T01C.01
T02C.012
T03C.01574
T04C.01968
T05C.046
T06C.07677
T07C.13
T08C.166
T09C.048
T10C.05
T11C.053
T12C.086
;LEADER: 12 
;HEADER: 
;CODE  : ASCII 
;FILE  : 17301-sa-1-6.drl for board D:/<user>/gelo/projects/Wiwynn/2017/17301-SA/final board/#Taaaabn07176.tmp ... layers TOP and BOTTOM
;T01 Holesize 1. = 10.000000 Tolerance = +0.000000/-0.000000 PLATED MILS Quantity = 54
;T02 Holesize 2. = 12.000000 Tolerance = +0.000000/-0.000000 PLATED MILS Quantity = 188
;T03 Holesize 3. = 15.740000 Tolerance = +0.000000/-0.000000 PLATED MILS Quantity = 28
;T04 Holesize 4. = 19.680000 Tolerance = +0.000000/-0.000000 PLATED MILS Quantity = 88
;T05 Holesize 5. = 46.000000 Tolerance = +0.000000/-0.000000 PLATED MILS Quantity = 4
;T06 Holesize 6. = 76.770000 Tolerance = +0.000000/-0.000000 PLATED MILS Quantity = 8
;T07 Holesize 7. = 130.000000 Tolerance = +0.000000/-0.000000 PLATED MILS Quantity = 4
;T08 Holesize 8. = 166.000000 Tolerance = +0.000000/-0.000000 PLATED MILS Quantity = 2
;T09 Holesize 9. = 48.000000 Tolerance = +0.000000/-0.000000 NON_PLATED MILS Quantity = 2
;T10 Holesize 10. = 50.000000 Tolerance = +0.000000/-0.000000 NON_PLATED MILS Quantity = 2
;T11 Holesize 11. = 53.000000 Tolerance = +0.000000/-0.000000 NON_PLATED MILS Quantity = 4
;T12 Holesize 12. = 86.000000 Tolerance = +0.000000/-0.000000 NON_PLATED MILS Quantity = 11
%
G90
T01
X73567Y4087
X74635Y29153
X75100Y36700
X76804Y61699
X60928Y64173
X76600Y68000
X204500Y90000
X208000
X217880Y83600
X213100Y83500
X222206Y41500
X218600Y37400
X220310Y4087
X258088Y21787
X268045Y8270
X273551Y37112
X293146Y81023
X293141Y97997
X279500Y116900
X279437Y120731
X310500Y184328
X322042Y147196
X309250Y127439
X308208Y101945
X321440Y101571
X329404Y101215
X325404
X327057Y90943
X303734Y89882
X327114Y87334
Y83334
X313617Y81023
X326892Y79371
X315166Y52172
X303900Y28900
X313900Y27200
X322100Y26600
X324700Y16300
X340000Y14667
X358900Y23928
X351040Y34753
X329962Y56703
X337406Y79575
X341133Y80298
X343028Y83447
Y87447
X345642Y90134
X337670Y90976
X340874Y92311
Y96311
X338145Y98740
X332822Y103140
X336238Y148951
X506868Y166599
T02
X42701Y5500
X44278Y24717
X48278
X44316Y28681
X48316
X44316Y32530
X48316
X5500Y48299
X45336Y52426
X49336
X45374Y56390
X49374
X45374Y60239
X49374
X37000Y75500
X41000
X37000Y79500
X41000
X7960Y85839
X27960
X65006Y43434
X63713Y48425
X60469Y79819
X52667Y83351
X56667
X60393Y83934
X67960Y85839
X87960
X107960
X127960
X147960
X167960
X187960
X208000Y86000
X204000
X208000Y82000
X204000
X244870Y80370
X248811Y80272
X244727Y76591
X248866Y76464
X247000Y47500
X243000
X214906Y39494
X211337Y38963
X207675Y38907
X246500Y27000
X242500
X286638Y33917
X281221Y33971
X258324Y38480
X261924
X258240Y42259
X261840
X278278Y47813
X281964Y47752
X258174Y48506
X261774
X278462Y51437
X282148Y51376
X258119Y52314
X261719
X278407Y55245
X282093Y55184
X280555Y61542
X284292Y61505
X299300Y144500
X284798Y149063
Y152687
X284940Y156881
X284905Y160541
X289800Y165000
X279122Y174213
X297698Y191563
X279122Y194213
X297698Y195187
X297840Y199381
X297805Y203041
X279122Y214213
Y234213
X282142Y251193
X342142
X322142
X326000Y217500
X314454Y213250
X304000Y213000
X300754Y205956
X339000Y203500
X335000
X318500
X314500
X339000Y198500
X335000
X318500
X314500
X339000Y193500
X335000
X318500
X314500
X318500Y188500
X314500
X326423Y183632
X332000Y183500
X340779Y165718
X336779
X300000Y164900
X303600Y164800
X320332Y164522
X316332
X340779Y162024
X336779
X320332Y160022
X316332
X340779Y158381
X336779
X320332Y155668
X316332
X340698Y154738
X336698
X320438Y151436
X316438
X309500Y145000
X303000Y144400
X303700Y140700
X302000Y133500
X315048Y133300
X301913Y129821
X348696Y105396
X321373Y56703
X349229Y52810
X332614Y52663
X328614
X349094Y49157
X332565Y49028
X328565
X349095Y45538
X332424Y45408
X328424
X348971Y41813
X332508Y41629
X328508
X332666Y27700
X345690Y20300
X332778Y20000
X347421Y8568
X322701Y5500
X357672Y4602
X350479Y10768
X364750Y37750
X352971Y41813
X353095Y45538
X353094Y49157
X353229Y52810
X350569Y102263
X354580Y102351
X352501Y105640
X356501
X358824Y108849
X350827Y108976
X354827
X362142Y251193
X382142
X402142
X422142
X442142
X482142
X462142
X480101Y230616
X483700Y230522
X476600Y227250
X471445Y93346
X538965Y41992
Y61992
X502868Y166448
X519980Y226295
X523642Y226351
Y230014
X520017Y230070
X502142Y251193
X522142
X559461Y208512
Y188512
Y168512
Y148512
Y128512
Y108512
Y88512
Y68512
T03
X121337Y23464
X124487
X127637
X130787
X133937
X137087
X140237
X121337Y67953
X124487
X127637
X130787
X133937
X137087
X140237
X412381Y151417
X415531
X418681
X421831
X424981
X428131
X431281
Y217165
X428131
X424981
X421831
X418681
X415531
X412381
T04
X88287Y10039
X93287
X98287
X103287
X108287
X113287
X118287
X143287
X148287
X153287
X158287
X163287
X168287
X173287
X178287
X183287
X188287
X193287
X198287
X203287
X208287
X213287
X88287Y54528
X93287
X98287
X103287
X108287
X113287
X118287
X143287
X148287
X153287
X158287
X163287
X168287
X173287
X178287
X183287
X188287
X193287
X198287
X203287
X208287
X213287
X379331Y137992
X384331
X389331
X394331
X399331
X404331
X409331
X434331
X439331
X444331
X449331
X454331
X459331
X464331
X469331
X474331
X479331
X484331
X489331
X494331
X499331
X504331
Y203740
X499331
X494331
X489331
X484331
X479331
X474331
X469331
X464331
X459331
X454331
X449331
X444331
X439331
X434331
X409331
X404331
X399331
X394331
X389331
X384331
X379331
T05
X484960Y86811
X496771
X508583
X520394
T06
X68112Y15039
Y59528
X233462Y15039
Y59528
X359156Y142992
Y208740
X524506
Y142992
T07
X15748Y67008
X303150Y242913
Y13780
X551181
T08
X15748Y15827
X551181Y242913
T09
X312657Y66142
Y107716
T10
X473149Y79094
X532205
T11
X225097Y15039
Y59528
X516141Y142992
Y208740
T12
X-12454Y45507
X17715Y44095
X395935Y76695
X508569Y15093
X552795Y40157
X525590Y240944
X554126Y315939
X-14755Y415558
X29461Y718854
X141466Y655356
X554126Y685624
M30
